FILE_TYPE = CONNECTIVITY;
{Allegro Design Entry HDL 17.4-2019 S026 (4007227) 1/17/2022}
"PAGE_NUMBER" = 17;
0"NC";
1"M_H_CPU0_SA_DQ<31:0>";
2"M_H_CPU0_SB_DQ<31:0>";
3"M_H_CPU0_SA_CB<7:0>";
4"M_H_CPU0_SB_CB<7:0>";
5"M_H_CPU0_SA_DQS_DN<9:0>";
6"M_H_CPU0_SA_DQS_DP<9:0>";
7"M_H_CPU0_SB_DQS_DN<9:0>";
8"M_H_CPU0_SB_DQS_DP<9:0>";
9"M_H_CPU0_SA_CA<6:0>";
10"M_H_CPU0_SB_CA<6:0>";
11"M_H_CPU0_ALERT_N";
12"M_H_CPU0_ALERT_R_N";
13"TP_M_H_CPU0_SA_TEST39H";
14"M_H_CPU0_CLK_DP<0>";
15"M_H_CPU0_CLK_DN<0>";
16"M_H_CPU0_SA_CS_N<0>";
17"M_H_CPU0_SA_CS_N<1>";
18"M_H_CPU0_SA_RSP<0>";
19"M_H_CPU0_SA_PAR";
20"M_H_CPU0_SB_CS_N<1>";
21"M_H_CPU0_SB_CS_N<0>";
22"M_H_CPU0_SB_RSP<0>";
23"M_H_CPU0_SB_PAR";
24"M_H_CPU0_RESET_N";
25"M_H_CPU0_SB_DQS_DP<9>";
26"M_H_CPU0_SB_DQS_DN<9>";
27"M_H_CPU0_SB_DQS_DN<8>";
28"M_H_CPU0_SB_CA<6>";
29"M_H_CPU0_SA_CA<6>";
30"M_H_CPU0_SB_CA<5>";
31"M_H_CPU0_SA_CA<5>";
32"M_H_CPU0_SB_CA<4>";
33"M_H_CPU0_SA_CA<4>";
34"M_H_CPU0_SB_CA<3>";
35"M_H_CPU0_SA_CA<3>";
36"M_H_CPU0_SB_CA<2>";
37"M_H_CPU0_SA_CA<2>";
38"M_H_CPU0_SB_CA<1>";
39"M_H_CPU0_SA_CA<1>";
40"M_H_CPU0_SB_CA<0>";
41"M_H_CPU0_SA_CA<0>";
42"M_H_CPU0_SB_DQS_DP<8>";
43"M_H_CPU0_SB_DQS_DP<7>";
44"M_H_CPU0_SB_DQS_DP<6>";
45"M_H_CPU0_SB_DQS_DP<5>";
46"M_H_CPU0_SB_DQS_DP<4>";
47"M_H_CPU0_SA_DQS_DP<9>";
48"M_H_CPU0_SB_DQS_DP<3>";
49"M_H_CPU0_SB_DQS_DN<7>";
50"M_H_CPU0_SB_DQS_DP<2>";
51"M_H_CPU0_SB_DQS_DN<6>";
52"M_H_CPU0_SB_DQS_DP<1>";
53"M_H_CPU0_SB_DQS_DN<5>";
54"M_H_CPU0_SB_DQS_DP<0>";
55"M_H_CPU0_SB_DQS_DN<4>";
56"M_H_CPU0_SA_DQS_DN<9>";
57"M_H_CPU0_SB_DQS_DN<3>";
58"M_H_CPU0_SB_DQS_DN<2>";
59"M_H_CPU0_SB_DQS_DN<1>";
60"M_H_CPU0_SB_DQS_DN<0>";
61"M_H_CPU0_SA_DQS_DN<1>";
62"M_H_CPU0_SA_DQS_DN<0>";
63"M_H_CPU0_SA_DQS_DP<8>";
64"M_H_CPU0_SA_DQS_DP<7>";
65"M_H_CPU0_SA_DQS_DP<6>";
66"M_H_CPU0_SA_DQS_DP<5>";
67"M_H_CPU0_SA_DQS_DP<4>";
68"M_H_CPU0_SA_DQS_DN<8>";
69"M_H_CPU0_SA_DQS_DP<3>";
70"M_H_CPU0_SA_DQS_DN<7>";
71"M_H_CPU0_SA_DQS_DP<2>";
72"M_H_CPU0_SA_DQS_DN<6>";
73"M_H_CPU0_SA_DQS_DP<1>";
74"M_H_CPU0_SA_DQS_DN<5>";
75"M_H_CPU0_SA_DQS_DP<0>";
76"M_H_CPU0_SA_DQS_DN<4>";
77"M_H_CPU0_SA_DQS_DN<3>";
78"M_H_CPU0_SA_DQS_DN<2>";
79"M_H_CPU0_SB_CB<7>";
80"M_H_CPU0_SB_CB<6>";
81"M_H_CPU0_SB_CB<5>";
82"M_H_CPU0_SB_CB<4>";
83"M_H_CPU0_SB_CB<3>";
84"M_H_CPU0_SB_CB<2>";
85"M_H_CPU0_SA_CB<7>";
86"M_H_CPU0_SB_CB<1>";
87"M_H_CPU0_SB_CB<0>";
88"M_H_CPU0_SA_CB<5>";
89"M_H_CPU0_SB_DQ<30>";
90"M_H_CPU0_SA_CB<4>";
91"M_H_CPU0_SA_CB<3>";
92"M_H_CPU0_SA_CB<2>";
93"M_H_CPU0_SA_CB<1>";
94"M_H_CPU0_SA_CB<0>";
95"M_H_CPU0_SB_DQ<29>";
96"M_H_CPU0_SB_DQ<28>";
97"M_H_CPU0_SB_DQ<27>";
98"M_H_CPU0_SB_DQ<26>";
99"M_H_CPU0_SB_DQ<25>";
100"M_H_CPU0_SB_DQ<24>";
101"M_H_CPU0_SB_DQ<23>";
102"M_H_CPU0_SB_DQ<22>";
103"M_H_CPU0_SB_DQ<21>";
104"M_H_CPU0_SA_CB<6>";
105"M_H_CPU0_SB_DQ<31>";
106"M_H_CPU0_SB_DQ<9>";
107"M_H_CPU0_SB_DQ<8>";
108"M_H_CPU0_SB_DQ<7>";
109"M_H_CPU0_SB_DQ<6>";
110"M_H_CPU0_SB_DQ<5>";
111"M_H_CPU0_SB_DQ<19>";
112"M_H_CPU0_SB_DQ<4>";
113"M_H_CPU0_SB_DQ<18>";
114"M_H_CPU0_SB_DQ<3>";
115"M_H_CPU0_SB_DQ<17>";
116"M_H_CPU0_SB_DQ<2>";
117"M_H_CPU0_SB_DQ<16>";
118"M_H_CPU0_SB_DQ<15>";
119"M_H_CPU0_SB_DQ<14>";
120"M_H_CPU0_SB_DQ<13>";
121"M_H_CPU0_SB_DQ<12>";
122"M_H_CPU0_SB_DQ<11>";
123"M_H_CPU0_SB_DQ<10>";
124"M_H_CPU0_SB_DQ<20>";
125"M_H_CPU0_SA_DQ<25>";
126"M_H_CPU0_SA_DQ<24>";
127"M_H_CPU0_SA_DQ<23>";
128"M_H_CPU0_SA_DQ<22>";
129"M_H_CPU0_SA_DQ<21>";
130"M_H_CPU0_SA_DQ<20>";
131"M_H_CPU0_SA_DQ<31>";
132"M_H_CPU0_SA_DQ<30>";
133"M_H_CPU0_SB_DQ<1>";
134"M_H_CPU0_SB_DQ<0>";
135"M_H_CPU0_SA_DQ<19>";
136"M_H_CPU0_SA_DQ<18>";
137"M_H_CPU0_SA_DQ<29>";
138"M_H_CPU0_SA_DQ<17>";
139"M_H_CPU0_SA_DQ<28>";
140"M_H_CPU0_SA_DQ<16>";
141"M_H_CPU0_SA_DQ<27>";
142"M_H_CPU0_SA_DQ<26>";
143"M_H_CPU0_SA_DQ<14>";
144"M_H_CPU0_SA_DQ<13>";
145"M_H_CPU0_SA_DQ<9>";
146"M_H_CPU0_SA_DQ<12>";
147"M_H_CPU0_SA_DQ<8>";
148"M_H_CPU0_SA_DQ<11>";
149"M_H_CPU0_SA_DQ<7>";
150"M_H_CPU0_SA_DQ<10>";
151"M_H_CPU0_SA_DQ<6>";
152"M_H_CPU0_SA_DQ<5>";
153"M_H_CPU0_SA_DQ<4>";
154"M_H_CPU0_SA_DQ<3>";
155"M_H_CPU0_SA_DQ<2>";
156"M_H_CPU0_SA_DQ<1>";
157"M_H_CPU0_SA_DQ<0>";
158"M_H_CPU0_SA_DQ<15>";
%"GENOA_SP5"
"8","(-4600,3600)","0","pure_quanta","I159";
;
LOCATION"U25"
$SEC"8"
CDS_SEC"8"
PART_TYPE"SMLF"
MATERIAL"IO"
VALUE"SOCKET6096_13568-001"
CDS_LIB"pure_quanta"
CDS_LMAN_SYM_OUTLINE"-650,2525,650,-2525"
NEEDS_NO_SIZE"TRUE"
PART_NUMBER"DGA^6000030";
"TEST39H"
$PN"BF14"13;
"MH1_CLK_L"
$PN"BG12"0;
"MH1_CLK_H"
$PN"BF13"0;
"MH0_CLK_L"
$PN"BD13"15;
"MH0_CLK_H"
$PN"BC12"14;
"MHB_PAR"
$PN"BL14"23;
"MHA_PAR"
$PN"BC14"19;
"MHB_DQS_H9"
$PN"BV13"25;
"MHA_CHECK5"
$PN"AP14"88;
"MHA_DATA14"
$PN"T13"143;
"MHA_DATA25"
$PN"AD14"125;
"MHA_DQS_L1"
$PN"P13"61;
"MHB0_CS_L1"
$PN"BN12"20;
"MHB1_CS_L0"
$PN"BL12"0;
"MHB_DATA30"
$PN"DE12"89;
"MHB_DQS_H8"
$PN"DD14"42;
"MHA_CHECK4"
$PN"AN12"90;
"MHA_DATA13"
$PN"T14"144;
"MHA_DATA24"
$PN"AC12"126;
"MHA_DQS_L0"
$PN"H13"62;
"MHB0_CS_L0"
$PN"BM14"21;
"MHB_DQS_H7"
$PN"CV14"43;
"MHA_CHECK3"
$PN"AL14"91;
"MHA_DATA9"
$PN"M14"145;
"MHA_DATA12"
$PN"R12"146;
"MHA_DATA23"
$PN"AC14"127;
"MHB_DATA9"
$PN"CJ14"106;
"MHB_DQS_H6"
$PN"CM14"44;
"MHA_CHECK2"
$PN"AK13"92;
"MHA_DATA8"
$PN"L12"147;
"MHA_DATA11"
$PN"N14"148;
"MHA_DATA22"
$PN"AB13"128;
"MHB_DATA8"
$PN"CH13"107;
"MHB_DQS_H5"
$PN"CF14"45;
"MHB_DQS_L9"
$PN"BW12"26;
"MHA_CHECK1"
$PN"AK14"93;
"MHA_DATA7"
$PN"L14"149;
"MHA_DATA10"
$PN"M13"150;
"MHA_DATA21"
$PN"AB14"129;
"MHB_DATA7"
$PN"CH14"108;
"MHB_DQS_H4"
$PN"BY14"46;
"MHB_DQS_L8"
$PN"DC14"27;
"MHA1_CS_L1"
$PN"AW14"0;
"MHA_CHECK0"
$PN"AJ12"94;
"MHA_DATA6"
$PN"K13"151;
"MHA_DATA20"
$PN"AA12"130;
"MHA_DATA31"
$PN"AJ14"131;
"MHA_DQS_H9"
$PN"AN14"47;
"MHB_DATA6"
$PN"CG12"109;
"MHB_DQS_H3"
$PN"DB13"48;
"MHB_DQS_L7"
$PN"CU14"49;
"MHA0_CS_L1"
$PN"AV14"17;
"MHA1_CS_L0"
$PN"AV13"0;
"MHA_DATA5"
$PN"K14"152;
"MHA_DATA30"
$PN"AH13"132;
"MHA_DQS_H8"
$PN"AG14"63;
"MHB_DATA5"
$PN"CG14"110;
"MHB_DATA19"
$PN"CT14"111;
"MHB_DQS_H2"
$PN"CT13"50;
"MHB_DQS_L6"
$PN"CL14"51;
"MHA0_CS_L0"
$PN"AU12"16;
"MHA_DATA4"
$PN"J12"153;
"MHA_DQS_H7"
$PN"AA14"64;
"MHB_CA6"
$PN"BK13"28;
"MHB_DATA4"
$PN"CF13"112;
"MHB_DATA18"
$PN"CR12"113;
"MHB_DATA29"
$PN"DE14"95;
"MHB_DQS_H1"
$PN"CK13"52;
"MHB_DQS_L5"
$PN"CE14"53;
"MHA_CA6"
$PN"BB14"29;
"MHA_DATA3"
$PN"G14"154;
"MHA_DQS_H6"
$PN"R14"65;
"MHB1_RSP_L"
$PN"BR12"0;
"MHB_CA5"
$PN"BK14"30;
"MHB_DATA3"
$PN"CD14"114;
"MHB_DATA17"
$PN"CR14"115;
"MHB_DATA28"
$PN"DD13"96;
"MHB_DQS_H0"
$PN"CD13"54;
"MHB_DQS_L4"
$PN"BW14"55;
"MHA_CA5"
$PN"BB13"31;
"MHA_DATA2"
$PN"F13"155;
"MHA_DQS_H5"
$PN"J14"66;
"MHA_DQS_L9"
$PN"AM14"56;
"MHB0_RSP_L"
$PN"BP13"22;
"MHB_CA4"
$PN"BJ14"32;
"MHB_CHECK7"
$PN"BV14"79;
"MHB_DATA2"
$PN"CC12"116;
"MHB_DATA16"
$PN"CP13"117;
"MHB_DATA27"
$PN"DB14"97;
"MHB_DQS_L3"
$PN"DC12"57;
"MHA_CA4"
$PN"BA12"33;
"MHA_DATA1"
$PN"F14"156;
"MHA_DQS_H4"
$PN"AL12"67;
"MHA_DQS_L8"
$PN"AF14"68;
"MHB_CA3"
$PN"BJ12"34;
"MHB_CHECK6"
$PN"BU12"80;
"MHB_DATA1"
$PN"CC14"133;
"MHB_DATA15"
$PN"CP14"118;
"MHB_DATA26"
$PN"DA12"98;
"MHB_DQS_L2"
$PN"CU12"58;
"MHA_CA3"
$PN"BA14"35;
"MHA_DATA0"
$PN"E12"157;
"MHA_DQS_H3"
$PN"AE12"69;
"MHA_DQS_L7"
$PN"Y14"70;
"MHB_CA2"
$PN"BH13"36;
"MHB_CHECK5"
$PN"BU14"81;
"MHB_DATA0"
$PN"CB13"134;
"MHB_DATA14"
$PN"CN12"119;
"MHB_DATA25"
$PN"DA14"99;
"MHB_DQS_L1"
$PN"CL12"59;
"MHA_CA2"
$PN"AY14"37;
"MHA_DATA19"
$PN"W14"135;
"MHA_DQS_H2"
$PN"W12"71;
"MHA_DQS_L6"
$PN"P14"72;
"MHB_CA1"
$PN"BH14"38;
"MHB_CHECK4"
$PN"BT13"82;
"MHB_DATA13"
$PN"CN14"120;
"MHB_DATA24"
$PN"CY13"100;
"MHB_DQS_L0"
$PN"CE12"60;
"MHA_CA1"
$PN"AY13"39;
"MHA_DATA18"
$PN"V13"136;
"MHA_DATA29"
$PN"AH14"137;
"MHA_DQS_H1"
$PN"N12"73;
"MHA_DQS_L5"
$PN"H14"74;
"MHB_CA0"
$PN"BG14"40;
"MHB_CHECK3"
$PN"CB14"83;
"MHB_DATA12"
$PN"CM13"121;
"MHB_DATA23"
$PN"CY14"101;
"MHA1_RSP_L"
$PN"BP14"0;
"MHA_CA0"
$PN"AW12"41;
"MHA_DATA17"
$PN"V14"138;
"MHA_DATA28"
$PN"AG12"139;
"MHA_DQS_H0"
$PN"G12"75;
"MHA_DQS_L4"
$PN"AM13"76;
"MHB_CHECK2"
$PN"CA12"84;
"MHB_DATA11"
$PN"CK14"122;
"MHB_DATA22"
$PN"CW12"102;
"MHA0_RSP_L"
$PN"BN14"18;
"MHA_CHECK7"
$PN"AR14"85;
"MHA_DATA16"
$PN"U12"140;
"MHA_DATA27"
$PN"AE14"141;
"MHA_DQS_L3"
$PN"AF13"77;
"MHB_CHECK1"
$PN"CA14"86;
"MHB_DATA10"
$PN"CJ12"123;
"MHB_DATA21"
$PN"CW14"103;
"MHA_CHECK6"
$PN"AP13"104;
"MHA_DATA15"
$PN"U14"158;
"MHA_DATA26"
$PN"AD13"142;
"MHA_DQS_L2"
$PN"Y13"78;
"MHB1_CS_L1"
$PN"BM13"0;
"MHB_CHECK0"
$PN"BY13"87;
"MHB_DATA20"
$PN"CV13"124;
"MHB_DATA31"
$PN"DF14"105;
"MH_RESET_L"
$PN"AU14"24;
"MH_ALERT_L"
$PN"AT14"12;
%"TAP"
"1","(-3325,5975)","0","mstr_standard","I162";
;
CDS_LIB"mstr_standard"
BODY_TYPE"PLUMBING"
HDL_TAP"TRUE";
"B \NAC \NWC"1;
"S \NAC"
BN"0"157;
%"TAP"
"1","(-3325,5925)","0","mstr_standard","I163";
;
CDS_LIB"mstr_standard"
BODY_TYPE"PLUMBING"
HDL_TAP"TRUE";
"B \NAC \NWC"1;
"S \NAC"
BN"1"156;
%"TAP"
"1","(-3325,5875)","0","mstr_standard","I164";
;
CDS_LIB"mstr_standard"
BODY_TYPE"PLUMBING"
HDL_TAP"TRUE";
"B \NAC \NWC"1;
"S \NAC"
BN"2"155;
%"TAP"
"1","(-3325,5825)","0","mstr_standard","I165";
;
CDS_LIB"mstr_standard"
BODY_TYPE"PLUMBING"
HDL_TAP"TRUE";
"B \NAC \NWC"1;
"S \NAC"
BN"3"154;
%"TAP"
"1","(-3325,5775)","0","mstr_standard","I166";
;
CDS_LIB"mstr_standard"
BODY_TYPE"PLUMBING"
HDL_TAP"TRUE";
"B \NAC \NWC"1;
"S \NAC"
BN"4"153;
%"TAP"
"1","(-3325,5675)","0","mstr_standard","I167";
;
CDS_LIB"mstr_standard"
BODY_TYPE"PLUMBING"
HDL_TAP"TRUE";
"B \NAC \NWC"1;
"S \NAC"
BN"6"151;
%"TAP"
"1","(-3325,5725)","0","mstr_standard","I168";
;
CDS_LIB"mstr_standard"
BODY_TYPE"PLUMBING"
HDL_TAP"TRUE";
"B \NAC \NWC"1;
"S \NAC"
BN"5"152;
%"TAP"
"1","(-3325,5425)","0","mstr_standard","I169";
;
CDS_LIB"mstr_standard"
BODY_TYPE"PLUMBING"
HDL_TAP"TRUE";
"B \NAC \NWC"1;
"S \NAC"
BN"10"150;
%"TAP"
"1","(-3325,5525)","0","mstr_standard","I170";
;
CDS_LIB"mstr_standard"
BODY_TYPE"PLUMBING"
HDL_TAP"TRUE";
"B \NAC \NWC"1;
"S \NAC"
BN"8"147;
%"TAP"
"1","(-3325,5625)","0","mstr_standard","I171";
;
CDS_LIB"mstr_standard"
BODY_TYPE"PLUMBING"
HDL_TAP"TRUE";
"B \NAC \NWC"1;
"S \NAC"
BN"7"149;
%"TAP"
"1","(-3325,5475)","0","mstr_standard","I172";
;
CDS_LIB"mstr_standard"
BODY_TYPE"PLUMBING"
HDL_TAP"TRUE";
"B \NAC \NWC"1;
"S \NAC"
BN"9"145;
%"TAP"
"1","(-3325,5225)","0","mstr_standard","I173";
;
CDS_LIB"mstr_standard"
BODY_TYPE"PLUMBING"
HDL_TAP"TRUE";
"B \NAC \NWC"1;
"S \NAC"
BN"14"143;
%"TAP"
"1","(-3325,5175)","0","mstr_standard","I174";
;
CDS_LIB"mstr_standard"
BODY_TYPE"PLUMBING"
HDL_TAP"TRUE";
"B \NAC \NWC"1;
"S \NAC"
BN"15"158;
%"TAP"
"1","(-3325,5275)","0","mstr_standard","I175";
;
CDS_LIB"mstr_standard"
BODY_TYPE"PLUMBING"
HDL_TAP"TRUE";
"B \NAC \NWC"1;
"S \NAC"
BN"13"144;
%"TAP"
"1","(-3325,5325)","0","mstr_standard","I176";
;
CDS_LIB"mstr_standard"
BODY_TYPE"PLUMBING"
HDL_TAP"TRUE";
"B \NAC \NWC"1;
"S \NAC"
BN"12"146;
%"TAP"
"1","(-3325,5375)","0","mstr_standard","I177";
;
CDS_LIB"mstr_standard"
BODY_TYPE"PLUMBING"
HDL_TAP"TRUE";
"B \NAC \NWC"1;
"S \NAC"
BN"11"148;
%"TAP"
"1","(-3325,4975)","0","mstr_standard","I178";
;
CDS_LIB"mstr_standard"
BODY_TYPE"PLUMBING"
HDL_TAP"TRUE";
"B \NAC \NWC"1;
"S \NAC"
BN"18"136;
%"TAP"
"1","(-3325,4925)","0","mstr_standard","I179";
;
CDS_LIB"mstr_standard"
BODY_TYPE"PLUMBING"
HDL_TAP"TRUE";
"B \NAC \NWC"1;
"S \NAC"
BN"19"135;
%"TAP"
"1","(-3325,4875)","0","mstr_standard","I180";
;
CDS_LIB"mstr_standard"
BODY_TYPE"PLUMBING"
HDL_TAP"TRUE";
"B \NAC \NWC"1;
"S \NAC"
BN"20"130;
%"TAP"
"1","(-3325,5025)","0","mstr_standard","I181";
;
CDS_LIB"mstr_standard"
BODY_TYPE"PLUMBING"
HDL_TAP"TRUE";
"B \NAC \NWC"1;
"S \NAC"
BN"17"138;
%"TAP"
"1","(-3325,5075)","0","mstr_standard","I182";
;
CDS_LIB"mstr_standard"
BODY_TYPE"PLUMBING"
HDL_TAP"TRUE";
"B \NAC \NWC"1;
"S \NAC"
BN"16"140;
%"TAP"
"1","(-3325,4625)","0","mstr_standard","I183";
;
CDS_LIB"mstr_standard"
BODY_TYPE"PLUMBING"
HDL_TAP"TRUE";
"B \NAC \NWC"1;
"S \NAC"
BN"24"126;
%"TAP"
"1","(-3325,4725)","0","mstr_standard","I184";
;
CDS_LIB"mstr_standard"
BODY_TYPE"PLUMBING"
HDL_TAP"TRUE";
"B \NAC \NWC"1;
"S \NAC"
BN"23"127;
%"TAP"
"1","(-3325,4775)","0","mstr_standard","I185";
;
CDS_LIB"mstr_standard"
BODY_TYPE"PLUMBING"
HDL_TAP"TRUE";
"B \NAC \NWC"1;
"S \NAC"
BN"22"128;
%"TAP"
"1","(-3325,4825)","0","mstr_standard","I186";
;
CDS_LIB"mstr_standard"
BODY_TYPE"PLUMBING"
HDL_TAP"TRUE";
"B \NAC \NWC"1;
"S \NAC"
BN"21"129;
%"TAP"
"1","(-3325,4475)","0","mstr_standard","I187";
;
CDS_LIB"mstr_standard"
BODY_TYPE"PLUMBING"
HDL_TAP"TRUE";
"B \NAC \NWC"1;
"S \NAC"
BN"27"141;
%"TAP"
"1","(-3325,4425)","0","mstr_standard","I188";
;
CDS_LIB"mstr_standard"
BODY_TYPE"PLUMBING"
HDL_TAP"TRUE";
"B \NAC \NWC"1;
"S \NAC"
BN"28"139;
%"TAP"
"1","(-3325,4375)","0","mstr_standard","I189";
;
CDS_LIB"mstr_standard"
BODY_TYPE"PLUMBING"
HDL_TAP"TRUE";
"B \NAC \NWC"1;
"S \NAC"
BN"29"137;
%"TAP"
"1","(-3325,4575)","0","mstr_standard","I190";
;
CDS_LIB"mstr_standard"
BODY_TYPE"PLUMBING"
HDL_TAP"TRUE";
"B \NAC \NWC"1;
"S \NAC"
BN"25"125;
%"TAP"
"1","(-3325,4525)","0","mstr_standard","I191";
;
CDS_LIB"mstr_standard"
BODY_TYPE"PLUMBING"
HDL_TAP"TRUE";
"B \NAC \NWC"1;
"S \NAC"
BN"26"142;
%"TAP"
"1","(-3325,4175)","0","mstr_standard","I192";
;
CDS_LIB"mstr_standard"
BODY_TYPE"PLUMBING"
HDL_TAP"TRUE";
"B \NAC \NWC"2;
"S \NAC"
BN"0"134;
%"TAP"
"1","(-3325,4125)","0","mstr_standard","I193";
;
CDS_LIB"mstr_standard"
BODY_TYPE"PLUMBING"
HDL_TAP"TRUE";
"B \NAC \NWC"2;
"S \NAC"
BN"1"133;
%"TAP"
"1","(-3325,4275)","0","mstr_standard","I194";
;
CDS_LIB"mstr_standard"
BODY_TYPE"PLUMBING"
HDL_TAP"TRUE";
"B \NAC \NWC"1;
"S \NAC"
BN"31"131;
%"TAP"
"1","(-3325,4325)","0","mstr_standard","I195";
;
CDS_LIB"mstr_standard"
BODY_TYPE"PLUMBING"
HDL_TAP"TRUE";
"B \NAC \NWC"1;
"S \NAC"
BN"30"132;
%"TAP"
"1","(-3325,4075)","0","mstr_standard","I197";
;
CDS_LIB"mstr_standard"
BODY_TYPE"PLUMBING"
HDL_TAP"TRUE";
"B \NAC \NWC"2;
"S \NAC"
BN"2"116;
%"TAP"
"1","(-3325,4025)","0","mstr_standard","I198";
;
CDS_LIB"mstr_standard"
BODY_TYPE"PLUMBING"
HDL_TAP"TRUE";
"B \NAC \NWC"2;
"S \NAC"
BN"3"114;
%"TAP"
"1","(-3325,3975)","0","mstr_standard","I199";
;
CDS_LIB"mstr_standard"
BODY_TYPE"PLUMBING"
HDL_TAP"TRUE";
"B \NAC \NWC"2;
"S \NAC"
BN"4"112;
%"TAP"
"1","(-3325,3875)","0","mstr_standard","I200";
;
CDS_LIB"mstr_standard"
BODY_TYPE"PLUMBING"
HDL_TAP"TRUE";
"B \NAC \NWC"2;
"S \NAC"
BN"6"109;
%"TAP"
"1","(-3325,3925)","0","mstr_standard","I201";
;
CDS_LIB"mstr_standard"
BODY_TYPE"PLUMBING"
HDL_TAP"TRUE";
"B \NAC \NWC"2;
"S \NAC"
BN"5"110;
%"TAP"
"1","(-3325,3675)","0","mstr_standard","I202";
;
CDS_LIB"mstr_standard"
BODY_TYPE"PLUMBING"
HDL_TAP"TRUE";
"B \NAC \NWC"2;
"S \NAC"
BN"9"106;
%"TAP"
"1","(-3325,3725)","0","mstr_standard","I203";
;
CDS_LIB"mstr_standard"
BODY_TYPE"PLUMBING"
HDL_TAP"TRUE";
"B \NAC \NWC"2;
"S \NAC"
BN"8"107;
%"TAP"
"1","(-3325,3825)","0","mstr_standard","I204";
;
CDS_LIB"mstr_standard"
BODY_TYPE"PLUMBING"
HDL_TAP"TRUE";
"B \NAC \NWC"2;
"S \NAC"
BN"7"108;
%"TAP"
"1","(-3325,3625)","0","mstr_standard","I205";
;
CDS_LIB"mstr_standard"
BODY_TYPE"PLUMBING"
HDL_TAP"TRUE";
"B \NAC \NWC"2;
"S \NAC"
BN"10"123;
%"TAP"
"1","(-3325,3375)","0","mstr_standard","I206";
;
CDS_LIB"mstr_standard"
BODY_TYPE"PLUMBING"
HDL_TAP"TRUE";
"B \NAC \NWC"2;
"S \NAC"
BN"15"118;
%"TAP"
"1","(-3325,3425)","0","mstr_standard","I207";
;
CDS_LIB"mstr_standard"
BODY_TYPE"PLUMBING"
HDL_TAP"TRUE";
"B \NAC \NWC"2;
"S \NAC"
BN"14"119;
%"TAP"
"1","(-3325,3475)","0","mstr_standard","I208";
;
CDS_LIB"mstr_standard"
BODY_TYPE"PLUMBING"
HDL_TAP"TRUE";
"B \NAC \NWC"2;
"S \NAC"
BN"13"120;
%"TAP"
"1","(-3325,3525)","0","mstr_standard","I209";
;
CDS_LIB"mstr_standard"
BODY_TYPE"PLUMBING"
HDL_TAP"TRUE";
"B \NAC \NWC"2;
"S \NAC"
BN"12"121;
%"TAP"
"1","(-3325,3575)","0","mstr_standard","I210";
;
CDS_LIB"mstr_standard"
BODY_TYPE"PLUMBING"
HDL_TAP"TRUE";
"B \NAC \NWC"2;
"S \NAC"
BN"11"122;
%"TAP"
"1","(-3325,3175)","0","mstr_standard","I211";
;
CDS_LIB"mstr_standard"
BODY_TYPE"PLUMBING"
HDL_TAP"TRUE";
"B \NAC \NWC"2;
"S \NAC"
BN"18"113;
%"TAP"
"1","(-3325,3125)","0","mstr_standard","I212";
;
CDS_LIB"mstr_standard"
BODY_TYPE"PLUMBING"
HDL_TAP"TRUE";
"B \NAC \NWC"2;
"S \NAC"
BN"19"111;
%"TAP"
"1","(-3325,3075)","0","mstr_standard","I213";
;
CDS_LIB"mstr_standard"
BODY_TYPE"PLUMBING"
HDL_TAP"TRUE";
"B \NAC \NWC"2;
"S \NAC"
BN"20"124;
%"TAP"
"1","(-3325,3275)","0","mstr_standard","I214";
;
CDS_LIB"mstr_standard"
BODY_TYPE"PLUMBING"
HDL_TAP"TRUE";
"B \NAC \NWC"2;
"S \NAC"
BN"16"117;
%"TAP"
"1","(-3325,3225)","0","mstr_standard","I215";
;
CDS_LIB"mstr_standard"
BODY_TYPE"PLUMBING"
HDL_TAP"TRUE";
"B \NAC \NWC"2;
"S \NAC"
BN"17"115;
%"TAP"
"1","(-3325,2975)","0","mstr_standard","I216";
;
CDS_LIB"mstr_standard"
BODY_TYPE"PLUMBING"
HDL_TAP"TRUE";
"B \NAC \NWC"2;
"S \NAC"
BN"22"102;
%"TAP"
"1","(-3325,2925)","0","mstr_standard","I217";
;
CDS_LIB"mstr_standard"
BODY_TYPE"PLUMBING"
HDL_TAP"TRUE";
"B \NAC \NWC"2;
"S \NAC"
BN"23"101;
%"TAP"
"1","(-3325,3025)","0","mstr_standard","I218";
;
CDS_LIB"mstr_standard"
BODY_TYPE"PLUMBING"
HDL_TAP"TRUE";
"B \NAC \NWC"2;
"S \NAC"
BN"21"103;
%"TAP"
"1","(-3325,2825)","0","mstr_standard","I219";
;
CDS_LIB"mstr_standard"
BODY_TYPE"PLUMBING"
HDL_TAP"TRUE";
"B \NAC \NWC"2;
"S \NAC"
BN"24"100;
%"TAP"
"1","(-3325,2675)","0","mstr_standard","I220";
;
CDS_LIB"mstr_standard"
BODY_TYPE"PLUMBING"
HDL_TAP"TRUE";
"B \NAC \NWC"2;
"S \NAC"
BN"27"97;
%"TAP"
"1","(-3325,2625)","0","mstr_standard","I221";
;
CDS_LIB"mstr_standard"
BODY_TYPE"PLUMBING"
HDL_TAP"TRUE";
"B \NAC \NWC"2;
"S \NAC"
BN"28"96;
%"TAP"
"1","(-3325,2575)","0","mstr_standard","I222";
;
CDS_LIB"mstr_standard"
BODY_TYPE"PLUMBING"
HDL_TAP"TRUE";
"B \NAC \NWC"2;
"S \NAC"
BN"29"95;
%"TAP"
"1","(-3325,2775)","0","mstr_standard","I223";
;
CDS_LIB"mstr_standard"
BODY_TYPE"PLUMBING"
HDL_TAP"TRUE";
"B \NAC \NWC"2;
"S \NAC"
BN"25"99;
%"TAP"
"1","(-3325,2725)","0","mstr_standard","I224";
;
CDS_LIB"mstr_standard"
BODY_TYPE"PLUMBING"
HDL_TAP"TRUE";
"B \NAC \NWC"2;
"S \NAC"
BN"26"98;
%"TAP"
"1","(-3325,2375)","0","mstr_standard","I225";
;
CDS_LIB"mstr_standard"
BODY_TYPE"PLUMBING"
HDL_TAP"TRUE";
"B \NAC \NWC"3;
"S \NAC"
BN"0"94;
%"TAP"
"1","(-3325,2325)","0","mstr_standard","I226";
;
CDS_LIB"mstr_standard"
BODY_TYPE"PLUMBING"
HDL_TAP"TRUE";
"B \NAC \NWC"3;
"S \NAC"
BN"1"93;
%"TAP"
"1","(-3325,2525)","0","mstr_standard","I227";
;
CDS_LIB"mstr_standard"
BODY_TYPE"PLUMBING"
HDL_TAP"TRUE";
"B \NAC \NWC"2;
"S \NAC"
BN"30"89;
%"TAP"
"1","(-3325,2475)","0","mstr_standard","I228";
;
CDS_LIB"mstr_standard"
BODY_TYPE"PLUMBING"
HDL_TAP"TRUE";
"B \NAC \NWC"2;
"S \NAC"
BN"31"105;
%"TAP"
"1","(-3325,2225)","0","mstr_standard","I229";
;
CDS_LIB"mstr_standard"
BODY_TYPE"PLUMBING"
HDL_TAP"TRUE";
"B \NAC \NWC"3;
"S \NAC"
BN"3"91;
%"TAP"
"1","(-3325,2275)","0","mstr_standard","I230";
;
CDS_LIB"mstr_standard"
BODY_TYPE"PLUMBING"
HDL_TAP"TRUE";
"B \NAC \NWC"3;
"S \NAC"
BN"2"92;
%"TAP"
"1","(-3325,2075)","0","mstr_standard","I231";
;
CDS_LIB"mstr_standard"
BODY_TYPE"PLUMBING"
HDL_TAP"TRUE";
"B \NAC \NWC"3;
"S \NAC"
BN"6"104;
%"TAP"
"1","(-3325,2125)","0","mstr_standard","I232";
;
CDS_LIB"mstr_standard"
BODY_TYPE"PLUMBING"
HDL_TAP"TRUE";
"B \NAC \NWC"3;
"S \NAC"
BN"5"88;
%"TAP"
"1","(-3325,2175)","0","mstr_standard","I233";
;
CDS_LIB"mstr_standard"
BODY_TYPE"PLUMBING"
HDL_TAP"TRUE";
"B \NAC \NWC"3;
"S \NAC"
BN"4"90;
%"TAP"
"1","(-3325,1875)","0","mstr_standard","I235";
;
CDS_LIB"mstr_standard"
BODY_TYPE"PLUMBING"
HDL_TAP"TRUE";
"B \NAC \NWC"4;
"S \NAC"
BN"1"86;
%"TAP"
"1","(-3325,1925)","0","mstr_standard","I236";
;
CDS_LIB"mstr_standard"
BODY_TYPE"PLUMBING"
HDL_TAP"TRUE";
"B \NAC \NWC"4;
"S \NAC"
BN"0"87;
%"TAP"
"1","(-3325,2025)","0","mstr_standard","I237";
;
CDS_LIB"mstr_standard"
BODY_TYPE"PLUMBING"
HDL_TAP"TRUE";
"B \NAC \NWC"3;
"S \NAC"
BN"7"85;
%"TAP"
"1","(-3325,1825)","0","mstr_standard","I238";
;
CDS_LIB"mstr_standard"
BODY_TYPE"PLUMBING"
HDL_TAP"TRUE";
"B \NAC \NWC"4;
"S \NAC"
BN"2"84;
%"TAP"
"1","(-3325,1775)","0","mstr_standard","I239";
;
CDS_LIB"mstr_standard"
BODY_TYPE"PLUMBING"
HDL_TAP"TRUE";
"B \NAC \NWC"4;
"S \NAC"
BN"3"83;
%"TAP"
"1","(-3325,1725)","0","mstr_standard","I240";
;
CDS_LIB"mstr_standard"
BODY_TYPE"PLUMBING"
HDL_TAP"TRUE";
"B \NAC \NWC"4;
"S \NAC"
BN"4"82;
%"TAP"
"1","(-3325,1675)","0","mstr_standard","I241";
;
CDS_LIB"mstr_standard"
BODY_TYPE"PLUMBING"
HDL_TAP"TRUE";
"B \NAC \NWC"4;
"S \NAC"
BN"5"81;
%"TAP"
"1","(-3325,1575)","0","mstr_standard","I242";
;
CDS_LIB"mstr_standard"
BODY_TYPE"PLUMBING"
HDL_TAP"TRUE";
"B \NAC \NWC"4;
"S \NAC"
BN"7"79;
%"TAP"
"1","(-3325,1625)","0","mstr_standard","I243";
;
CDS_LIB"mstr_standard"
BODY_TYPE"PLUMBING"
HDL_TAP"TRUE";
"B \NAC \NWC"4;
"S \NAC"
BN"6"80;
%"TAP"
"1","(-5750,5975)","2","mstr_standard","I244";
;
CDS_LIB"mstr_standard"
BODY_TYPE"PLUMBING"
HDL_TAP"TRUE";
"B \NAC \NWC"6;
"S \NAC"
BN"0"75;
%"TAP"
"1","(-5750,5775)","2","mstr_standard","I245";
;
CDS_LIB"mstr_standard"
BODY_TYPE"PLUMBING"
HDL_TAP"TRUE";
"B \NAC \NWC"6;
"S \NAC"
BN"2"71;
%"TAP"
"1","(-5750,5875)","2","mstr_standard","I246";
;
CDS_LIB"mstr_standard"
BODY_TYPE"PLUMBING"
HDL_TAP"TRUE";
"B \NAC \NWC"6;
"S \NAC"
BN"1"73;
%"TAP"
"1","(-5750,5675)","2","mstr_standard","I247";
;
CDS_LIB"mstr_standard"
BODY_TYPE"PLUMBING"
HDL_TAP"TRUE";
"B \NAC \NWC"6;
"S \NAC"
BN"3"69;
%"TAP"
"1","(-5950,5925)","2","mstr_standard","I248";
;
CDS_LIB"mstr_standard"
BODY_TYPE"PLUMBING"
HDL_TAP"TRUE";
"B \NAC \NWC"5;
"S \NAC"
BN"0"62;
%"TAP"
"1","(-5950,5825)","2","mstr_standard","I249";
;
CDS_LIB"mstr_standard"
BODY_TYPE"PLUMBING"
HDL_TAP"TRUE";
"B \NAC \NWC"5;
"S \NAC"
BN"1"61;
%"TAP"
"1","(-5950,5725)","2","mstr_standard","I250";
;
CDS_LIB"mstr_standard"
BODY_TYPE"PLUMBING"
HDL_TAP"TRUE";
"B \NAC \NWC"5;
"S \NAC"
BN"2"78;
%"TAP"
"1","(-5750,5575)","2","mstr_standard","I251";
;
CDS_LIB"mstr_standard"
BODY_TYPE"PLUMBING"
HDL_TAP"TRUE";
"B \NAC \NWC"6;
"S \NAC"
BN"4"67;
%"TAP"
"1","(-5750,5475)","2","mstr_standard","I252";
;
CDS_LIB"mstr_standard"
BODY_TYPE"PLUMBING"
HDL_TAP"TRUE";
"B \NAC \NWC"6;
"S \NAC"
BN"5"66;
%"TAP"
"1","(-5950,5625)","2","mstr_standard","I253";
;
CDS_LIB"mstr_standard"
BODY_TYPE"PLUMBING"
HDL_TAP"TRUE";
"B \NAC \NWC"5;
"S \NAC"
BN"3"77;
%"TAP"
"1","(-5750,5375)","2","mstr_standard","I254";
;
CDS_LIB"mstr_standard"
BODY_TYPE"PLUMBING"
HDL_TAP"TRUE";
"B \NAC \NWC"6;
"S \NAC"
BN"6"65;
%"TAP"
"1","(-5750,5275)","2","mstr_standard","I255";
;
CDS_LIB"mstr_standard"
BODY_TYPE"PLUMBING"
HDL_TAP"TRUE";
"B \NAC \NWC"6;
"S \NAC"
BN"7"64;
%"TAP"
"1","(-5750,5175)","2","mstr_standard","I256";
;
CDS_LIB"mstr_standard"
BODY_TYPE"PLUMBING"
HDL_TAP"TRUE";
"B \NAC \NWC"6;
"S \NAC"
BN"8"63;
%"TAP"
"1","(-5950,5525)","2","mstr_standard","I257";
;
CDS_LIB"mstr_standard"
BODY_TYPE"PLUMBING"
HDL_TAP"TRUE";
"B \NAC \NWC"5;
"S \NAC"
BN"4"76;
%"TAP"
"1","(-5950,5425)","2","mstr_standard","I258";
;
CDS_LIB"mstr_standard"
BODY_TYPE"PLUMBING"
HDL_TAP"TRUE";
"B \NAC \NWC"5;
"S \NAC"
BN"5"74;
%"TAP"
"1","(-5950,5325)","2","mstr_standard","I259";
;
CDS_LIB"mstr_standard"
BODY_TYPE"PLUMBING"
HDL_TAP"TRUE";
"B \NAC \NWC"5;
"S \NAC"
BN"6"72;
%"TAP"
"1","(-5950,5125)","2","mstr_standard","I260";
;
CDS_LIB"mstr_standard"
BODY_TYPE"PLUMBING"
HDL_TAP"TRUE";
"B \NAC \NWC"5;
"S \NAC"
BN"8"68;
%"TAP"
"1","(-5950,5225)","2","mstr_standard","I261";
;
CDS_LIB"mstr_standard"
BODY_TYPE"PLUMBING"
HDL_TAP"TRUE";
"B \NAC \NWC"5;
"S \NAC"
BN"7"70;
%"TAP"
"1","(-5750,5075)","2","mstr_standard","I262";
;
CDS_LIB"mstr_standard"
BODY_TYPE"PLUMBING"
HDL_TAP"TRUE";
"B \NAC \NWC"6;
"S \NAC"
BN"9"47;
%"TAP"
"1","(-5750,4925)","2","mstr_standard","I263";
;
CDS_LIB"mstr_standard"
BODY_TYPE"PLUMBING"
HDL_TAP"TRUE";
"B \NAC \NWC"8;
"S \NAC"
BN"0"54;
%"TAP"
"1","(-5750,4825)","2","mstr_standard","I264";
;
CDS_LIB"mstr_standard"
BODY_TYPE"PLUMBING"
HDL_TAP"TRUE";
"B \NAC \NWC"8;
"S \NAC"
BN"1"52;
%"TAP"
"1","(-5750,4725)","2","mstr_standard","I265";
;
CDS_LIB"mstr_standard"
BODY_TYPE"PLUMBING"
HDL_TAP"TRUE";
"B \NAC \NWC"8;
"S \NAC"
BN"2"50;
%"TAP"
"1","(-5750,4625)","2","mstr_standard","I266";
;
CDS_LIB"mstr_standard"
BODY_TYPE"PLUMBING"
HDL_TAP"TRUE";
"B \NAC \NWC"8;
"S \NAC"
BN"3"48;
%"TAP"
"1","(-5950,5025)","2","mstr_standard","I267";
;
CDS_LIB"mstr_standard"
BODY_TYPE"PLUMBING"
HDL_TAP"TRUE";
"B \NAC \NWC"5;
"S \NAC"
BN"9"56;
%"TAP"
"1","(-5950,4875)","2","mstr_standard","I268";
;
CDS_LIB"mstr_standard"
BODY_TYPE"PLUMBING"
HDL_TAP"TRUE";
"B \NAC \NWC"7;
"S \NAC"
BN"0"60;
%"TAP"
"1","(-5950,4775)","2","mstr_standard","I269";
;
CDS_LIB"mstr_standard"
BODY_TYPE"PLUMBING"
HDL_TAP"TRUE";
"B \NAC \NWC"7;
"S \NAC"
BN"1"59;
%"TAP"
"1","(-5950,4675)","2","mstr_standard","I270";
;
CDS_LIB"mstr_standard"
BODY_TYPE"PLUMBING"
HDL_TAP"TRUE";
"B \NAC \NWC"7;
"S \NAC"
BN"2"58;
%"TAP"
"1","(-5750,4525)","2","mstr_standard","I271";
;
CDS_LIB"mstr_standard"
BODY_TYPE"PLUMBING"
HDL_TAP"TRUE";
"B \NAC \NWC"8;
"S \NAC"
BN"4"46;
%"TAP"
"1","(-5750,4425)","2","mstr_standard","I272";
;
CDS_LIB"mstr_standard"
BODY_TYPE"PLUMBING"
HDL_TAP"TRUE";
"B \NAC \NWC"8;
"S \NAC"
BN"5"45;
%"TAP"
"1","(-5750,4325)","2","mstr_standard","I273";
;
CDS_LIB"mstr_standard"
BODY_TYPE"PLUMBING"
HDL_TAP"TRUE";
"B \NAC \NWC"8;
"S \NAC"
BN"6"44;
%"TAP"
"1","(-5750,4225)","2","mstr_standard","I274";
;
CDS_LIB"mstr_standard"
BODY_TYPE"PLUMBING"
HDL_TAP"TRUE";
"B \NAC \NWC"8;
"S \NAC"
BN"7"43;
%"TAP"
"1","(-5750,4125)","2","mstr_standard","I275";
;
CDS_LIB"mstr_standard"
BODY_TYPE"PLUMBING"
HDL_TAP"TRUE";
"B \NAC \NWC"8;
"S \NAC"
BN"8"42;
%"TAP"
"1","(-5950,4575)","2","mstr_standard","I276";
;
CDS_LIB"mstr_standard"
BODY_TYPE"PLUMBING"
HDL_TAP"TRUE";
"B \NAC \NWC"7;
"S \NAC"
BN"3"57;
%"TAP"
"1","(-5950,4475)","2","mstr_standard","I277";
;
CDS_LIB"mstr_standard"
BODY_TYPE"PLUMBING"
HDL_TAP"TRUE";
"B \NAC \NWC"7;
"S \NAC"
BN"4"55;
%"TAP"
"1","(-5950,4375)","2","mstr_standard","I278";
;
CDS_LIB"mstr_standard"
BODY_TYPE"PLUMBING"
HDL_TAP"TRUE";
"B \NAC \NWC"7;
"S \NAC"
BN"5"53;
%"TAP"
"1","(-5950,4275)","2","mstr_standard","I279";
;
CDS_LIB"mstr_standard"
BODY_TYPE"PLUMBING"
HDL_TAP"TRUE";
"B \NAC \NWC"7;
"S \NAC"
BN"6"51;
%"TAP"
"1","(-5950,4175)","2","mstr_standard","I280";
;
CDS_LIB"mstr_standard"
BODY_TYPE"PLUMBING"
HDL_TAP"TRUE";
"B \NAC \NWC"7;
"S \NAC"
BN"7"49;
%"TAP"
"1","(-5750,4025)","2","mstr_standard","I285";
;
CDS_LIB"mstr_standard"
BODY_TYPE"PLUMBING"
HDL_TAP"TRUE";
"B \NAC \NWC"8;
"S \NAC"
BN"9"25;
%"TAP"
"1","(-5950,4075)","2","mstr_standard","I286";
;
CDS_LIB"mstr_standard"
BODY_TYPE"PLUMBING"
HDL_TAP"TRUE";
"B \NAC \NWC"7;
"S \NAC"
BN"8"27;
%"TAP"
"1","(-5950,3975)","2","mstr_standard","I287";
;
CDS_LIB"mstr_standard"
BODY_TYPE"PLUMBING"
HDL_TAP"TRUE";
"B \NAC \NWC"7;
"S \NAC"
BN"9"26;
%"TAP"
"1","(-5950,3825)","2","mstr_standard","I288";
;
CDS_LIB"mstr_standard"
BODY_TYPE"PLUMBING"
HDL_TAP"TRUE";
"B \NAC \NWC"9;
"S \NAC"
BN"0"41;
%"TAP"
"1","(-5950,3775)","2","mstr_standard","I289";
;
CDS_LIB"mstr_standard"
BODY_TYPE"PLUMBING"
HDL_TAP"TRUE";
"B \NAC \NWC"9;
"S \NAC"
BN"1"39;
%"TAP"
"1","(-5950,3725)","2","mstr_standard","I290";
;
CDS_LIB"mstr_standard"
BODY_TYPE"PLUMBING"
HDL_TAP"TRUE";
"B \NAC \NWC"9;
"S \NAC"
BN"2"37;
%"TAP"
"1","(-5950,3675)","2","mstr_standard","I291";
;
CDS_LIB"mstr_standard"
BODY_TYPE"PLUMBING"
HDL_TAP"TRUE";
"B \NAC \NWC"9;
"S \NAC"
BN"3"35;
%"TAP"
"1","(-5950,3625)","2","mstr_standard","I292";
;
CDS_LIB"mstr_standard"
BODY_TYPE"PLUMBING"
HDL_TAP"TRUE";
"B \NAC \NWC"9;
"S \NAC"
BN"4"33;
%"TAP"
"1","(-5950,3575)","2","mstr_standard","I293";
;
CDS_LIB"mstr_standard"
BODY_TYPE"PLUMBING"
HDL_TAP"TRUE";
"B \NAC \NWC"9;
"S \NAC"
BN"5"31;
%"TAP"
"1","(-5950,3525)","2","mstr_standard","I294";
;
CDS_LIB"mstr_standard"
BODY_TYPE"PLUMBING"
HDL_TAP"TRUE";
"B \NAC \NWC"9;
"S \NAC"
BN"6"29;
%"TAP"
"1","(-5950,3325)","2","mstr_standard","I295";
;
CDS_LIB"mstr_standard"
BODY_TYPE"PLUMBING"
HDL_TAP"TRUE";
"B \NAC \NWC"10;
"S \NAC"
BN"2"36;
%"TAP"
"1","(-5950,3425)","2","mstr_standard","I296";
;
CDS_LIB"mstr_standard"
BODY_TYPE"PLUMBING"
HDL_TAP"TRUE";
"B \NAC \NWC"10;
"S \NAC"
BN"0"40;
%"TAP"
"1","(-5950,3375)","2","mstr_standard","I297";
;
CDS_LIB"mstr_standard"
BODY_TYPE"PLUMBING"
HDL_TAP"TRUE";
"B \NAC \NWC"10;
"S \NAC"
BN"1"38;
%"TAP"
"1","(-5950,3275)","2","mstr_standard","I298";
;
CDS_LIB"mstr_standard"
BODY_TYPE"PLUMBING"
HDL_TAP"TRUE";
"B \NAC \NWC"10;
"S \NAC"
BN"3"34;
%"TAP"
"1","(-5950,3225)","2","mstr_standard","I299";
;
CDS_LIB"mstr_standard"
BODY_TYPE"PLUMBING"
HDL_TAP"TRUE";
"B \NAC \NWC"10;
"S \NAC"
BN"4"32;
%"TAP"
"1","(-5950,3125)","2","mstr_standard","I300";
;
CDS_LIB"mstr_standard"
BODY_TYPE"PLUMBING"
HDL_TAP"TRUE";
"B \NAC \NWC"10;
"S \NAC"
BN"6"28;
%"TAP"
"1","(-5950,3175)","2","mstr_standard","I301";
;
CDS_LIB"mstr_standard"
BODY_TYPE"PLUMBING"
HDL_TAP"TRUE";
"B \NAC \NWC"10;
"S \NAC"
BN"5"30;
%"Q_RES"
"1","(-6875,2125)","0","pure_quanta","I314";
;
LOCATION"R382"
$SEC"1"
CDS_SEC"1"
PACK_TYPE"0402LF"
TOLERANCE"1%"
VALUE"15"
MATERIAL"CHIP"
WATTAGE"1/16W"
CDS_LIB"pure_quanta"
PART_NUMBER"CS01502FB03";
"B"
$PN"2"12;
"A"
$PN"1"11;
END.
